(kicad_pcb
	(version 20260206)
	(generator "pcbnew")
	(generator_version "10.0")
	(general
		(thickness 1.6)
		(legacy_teardrops no)
	)
	(paper "A4")
	(title_block
		(title "01162023_DA0F0TEBIF0_F0T_Expander_BD_F_brd_V02_OCP.brd")
		(comment 1 "Grand Teton / footprints 3357-3363 of 9728")
	)
	(layers
		(0 "F.Cu" signal "TOP")
		(4 "In1.Cu" signal "GND")
		(6 "In2.Cu" signal "VCC")
		(8 "In3.Cu" signal "VCC1")
		(10 "In4.Cu" signal "GND1")
		(12 "In5.Cu" signal "IN1")
		(14 "In6.Cu" signal "GND2")
		(16 "In7.Cu" signal "IN2")
		(18 "In8.Cu" signal "GND3")
		(20 "In9.Cu" signal "IN3")
		(22 "In10.Cu" signal "GND4")
		(24 "In11.Cu" signal "IN4")
		(26 "In12.Cu" signal "GND5")
		(28 "In13.Cu" signal "IN5")
		(30 "In14.Cu" signal "GND6")
		(32 "In15.Cu" signal "IN6")
		(34 "In16.Cu" signal "GND7")
		(2 "B.Cu" signal "BOTTOM")
		(9 "F.Adhes" user "F.Adhesive")
		(11 "B.Adhes" user "B.Adhesive")
		(13 "F.Paste" user "Package Geometry/Pastemask Top")
		(15 "B.Paste" user "Package Geometry/Pastemask Bottom")
		(5 "F.SilkS" user "Ref Des/Silkscreen Top")
		(7 "B.SilkS" user "Ref Des/Silkscreen Bottom")
		(1 "F.Mask" user "Board Geometry/Soldermask Top")
		(3 "B.Mask" user "Board Geometry/Soldermask Bottom")
		(17 "Dwgs.User" user "User.Drawings")
		(19 "Cmts.User" user "User.Comments")
		(21 "Eco1.User" user "User.Eco1")
		(23 "Eco2.User" user "User.Eco2")
		(25 "Edge.Cuts" user "Board Geometry/Outline")
		(27 "Margin" user)
		(31 "F.CrtYd" user "Package Geometry/Place Bound Top")
		(29 "B.CrtYd" user "Package Geometry/Place Bound Bottom")
		(35 "F.Fab" user "Ref Des/Assembly Top")
		(33 "B.Fab" user "Ref Des/Assembly Bottom")
	)
	(footprint ""
		(layer "F.Cu")
		(at 108.120942 -116.230654 -90)
		(property "Reference" "R904"
			(at 0 0 270)
			(layer "F.SilkS")
			(hide yes)
			(effects
				(font
					(size 1.27 1.27)
				)
			)
		)
		(property "Value" ""
			(at 0 0 270)
			(layer "F.Fab")
			(effects
				(font
					(size 1.27 1.27)
				)
			)
		)
		(duplicate_pad_numbers_are_jumpers no)
		(fp_line
			(start -0.7874 0.4064)
			(end -0.7874 -0.4064)
			(stroke
				(width 0.1524)
				(type default)
			)
			(layer "F.SilkS")
		)
		(fp_line
			(start 0.7874 0.4064)
			(end -0.7874 0.4064)
			(stroke
				(width 0.1524)
				(type default)
			)
			(layer "F.SilkS")
		)
		(fp_line
			(start -0.7874 -0.4064)
			(end 0.7874 -0.4064)
			(stroke
				(width 0.1524)
				(type default)
			)
			(layer "F.SilkS")
		)
		(fp_line
			(start 0.7874 -0.4064)
			(end 0.7874 0.4064)
			(stroke
				(width 0.1524)
				(type default)
			)
			(layer "F.SilkS")
		)
		(fp_line
			(start -0.67945 0.3048)
			(end -0.67945 -0.305054)
			(stroke
				(width 0.1)
				(type default)
			)
			(layer "F.Fab")
		)
		(fp_line
			(start -0.12065 0.3048)
			(end -0.67945 0.3048)
			(stroke
				(width 0.1)
				(type default)
			)
			(layer "F.Fab")
		)
		(fp_line
			(start 0.120396 0.3048)
			(end 0.120396 0.2794)
			(stroke
				(width 0.1)
				(type default)
			)
			(layer "F.Fab")
		)
		(fp_line
			(start 0.67945 0.3048)
			(end 0.120396 0.3048)
			(stroke
				(width 0.1)
				(type default)
			)
			(layer "F.Fab")
		)
		(fp_line
			(start -0.12065 0.2794)
			(end -0.12065 0.3048)
			(stroke
				(width 0.1)
				(type default)
			)
			(layer "F.Fab")
		)
		(fp_line
			(start 0.120396 0.2794)
			(end -0.12065 0.2794)
			(stroke
				(width 0.1)
				(type default)
			)
			(layer "F.Fab")
		)
		(fp_line
			(start -0.12065 -0.2794)
			(end 0.12065 -0.2794)
			(stroke
				(width 0.1)
				(type default)
			)
			(layer "F.Fab")
		)
		(fp_line
			(start 0.12065 -0.2794)
			(end 0.12065 -0.3048)
			(stroke
				(width 0.1)
				(type default)
			)
			(layer "F.Fab")
		)
		(fp_line
			(start 0.12065 -0.3048)
			(end 0.67945 -0.3048)
			(stroke
				(width 0.1)
				(type default)
			)
			(layer "F.Fab")
		)
		(fp_line
			(start 0.67945 -0.3048)
			(end 0.67945 0.3048)
			(stroke
				(width 0.1)
				(type default)
			)
			(layer "F.Fab")
		)
		(fp_line
			(start -0.67945 -0.305054)
			(end -0.12065 -0.305054)
			(stroke
				(width 0.1)
				(type default)
			)
			(layer "F.Fab")
		)
		(fp_line
			(start -0.12065 -0.305054)
			(end -0.12065 -0.2794)
			(stroke
				(width 0.1)
				(type default)
			)
			(layer "F.Fab")
		)
		(pad "1" smd circle
			(at -0.40005 0 270)
			(size 0 0)
			(layers "F.Cu" "F.Mask" "F.Paste")
			(net "P3V3_AUX")
		)
		(pad "2" smd circle
			(at 0.40005 0 270)
			(size 0 0)
			(layers "F.Cu" "F.Mask" "F.Paste")
			(net "PWRGD_P12V_NIC1_CO")
		)
	)
	(footprint ""
		(layer "F.Cu")
		(at 330.71435 -66.32194 90)
		(property "Reference" "R6001"
			(at 0 0 90)
			(layer "F.SilkS")
			(hide yes)
			(effects
				(font
					(size 1.27 1.27)
				)
			)
		)
		(property "Value" ""
			(at 0 0 90)
			(layer "F.Fab")
			(effects
				(font
					(size 1.27 1.27)
				)
			)
		)
		(duplicate_pad_numbers_are_jumpers no)
		(fp_line
			(start 0.7874 -0.4064)
			(end 0.7874 0.4064)
			(stroke
				(width 0.1524)
				(type default)
			)
			(layer "F.SilkS")
		)
		(fp_line
			(start -0.7874 -0.4064)
			(end 0.7874 -0.4064)
			(stroke
				(width 0.1524)
				(type default)
			)
			(layer "F.SilkS")
		)
		(fp_line
			(start 0.7874 0.4064)
			(end -0.7874 0.4064)
			(stroke
				(width 0.1524)
				(type default)
			)
			(layer "F.SilkS")
		)
		(fp_line
			(start -0.7874 0.4064)
			(end -0.7874 -0.4064)
			(stroke
				(width 0.1524)
				(type default)
			)
			(layer "F.SilkS")
		)
		(fp_line
			(start -0.12065 -0.305054)
			(end -0.12065 -0.2794)
			(stroke
				(width 0.1)
				(type default)
			)
			(layer "F.Fab")
		)
		(fp_line
			(start -0.67945 -0.305054)
			(end -0.12065 -0.305054)
			(stroke
				(width 0.1)
				(type default)
			)
			(layer "F.Fab")
		)
		(fp_line
			(start 0.67945 -0.3048)
			(end 0.67945 0.3048)
			(stroke
				(width 0.1)
				(type default)
			)
			(layer "F.Fab")
		)
		(fp_line
			(start 0.12065 -0.3048)
			(end 0.67945 -0.3048)
			(stroke
				(width 0.1)
				(type default)
			)
			(layer "F.Fab")
		)
		(fp_line
			(start 0.12065 -0.2794)
			(end 0.12065 -0.3048)
			(stroke
				(width 0.1)
				(type default)
			)
			(layer "F.Fab")
		)
		(fp_line
			(start -0.12065 -0.2794)
			(end 0.12065 -0.2794)
			(stroke
				(width 0.1)
				(type default)
			)
			(layer "F.Fab")
		)
		(fp_line
			(start 0.120396 0.2794)
			(end -0.12065 0.2794)
			(stroke
				(width 0.1)
				(type default)
			)
			(layer "F.Fab")
		)
		(fp_line
			(start -0.12065 0.2794)
			(end -0.12065 0.3048)
			(stroke
				(width 0.1)
				(type default)
			)
			(layer "F.Fab")
		)
		(fp_line
			(start 0.67945 0.3048)
			(end 0.120396 0.3048)
			(stroke
				(width 0.1)
				(type default)
			)
			(layer "F.Fab")
		)
		(fp_line
			(start 0.120396 0.3048)
			(end 0.120396 0.2794)
			(stroke
				(width 0.1)
				(type default)
			)
			(layer "F.Fab")
		)
		(fp_line
			(start -0.12065 0.3048)
			(end -0.67945 0.3048)
			(stroke
				(width 0.1)
				(type default)
			)
			(layer "F.Fab")
		)
		(fp_line
			(start -0.67945 0.3048)
			(end -0.67945 -0.305054)
			(stroke
				(width 0.1)
				(type default)
			)
			(layer "F.Fab")
		)
		(pad "1" smd circle
			(at -0.40005 0 90)
			(size 0 0)
			(layers "F.Cu" "F.Mask" "F.Paste")
			(net "SSD11_PWR_EN_R")
		)
		(pad "2" smd circle
			(at 0.40005 0 90)
			(size 0 0)
			(layers "F.Cu" "F.Mask" "F.Paste")
			(net "P12V_SSD11_CO_EN")
		)
	)
	(footprint ""
		(layer "F.Cu")
		(at 11.997436 -251.312426 -90)
		(property "Reference" "C4229"
			(at 0 0 270)
			(layer "F.SilkS")
			(hide yes)
			(effects
				(font
					(size 1.27 1.27)
				)
			)
		)
		(property "Value" ""
			(at 0 0 270)
			(layer "F.Fab")
			(effects
				(font
					(size 1.27 1.27)
				)
			)
		)
		(duplicate_pad_numbers_are_jumpers no)
		(fp_line
			(start -1.2954 0.5842)
			(end -1.2954 -0.5842)
			(stroke
				(width 0.1524)
				(type default)
			)
			(layer "F.SilkS")
		)
		(fp_line
			(start 1.2954 0.5842)
			(end -1.2954 0.5842)
			(stroke
				(width 0.1524)
				(type default)
			)
			(layer "F.SilkS")
		)
		(fp_line
			(start -1.2954 -0.5842)
			(end 1.2954 -0.5842)
			(stroke
				(width 0.1524)
				(type default)
			)
			(layer "F.SilkS")
		)
		(fp_line
			(start 1.2954 -0.5842)
			(end 1.2954 0.5842)
			(stroke
				(width 0.1524)
				(type default)
			)
			(layer "F.SilkS")
		)
		(fp_line
			(start -0.8636 0.4572)
			(end -0.8636 0.4064)
			(stroke
				(width 0.1)
				(type default)
			)
			(layer "F.Fab")
		)
		(fp_line
			(start 0.8636 0.4572)
			(end -0.8636 0.4572)
			(stroke
				(width 0.1)
				(type default)
			)
			(layer "F.Fab")
		)
		(fp_line
			(start -1.1938 0.4064)
			(end -1.1938 -0.4064)
			(stroke
				(width 0.1)
				(type default)
			)
			(layer "F.Fab")
		)
		(fp_line
			(start -0.8636 0.4064)
			(end -1.1938 0.4064)
			(stroke
				(width 0.1)
				(type default)
			)
			(layer "F.Fab")
		)
		(fp_line
			(start 0.8636 0.4064)
			(end 0.8636 0.4572)
			(stroke
				(width 0.1)
				(type default)
			)
			(layer "F.Fab")
		)
		(fp_line
			(start 1.1938 0.4064)
			(end 0.8636 0.4064)
			(stroke
				(width 0.1)
				(type default)
			)
			(layer "F.Fab")
		)
		(fp_line
			(start -1.1938 -0.4064)
			(end -0.8636 -0.4064)
			(stroke
				(width 0.1)
				(type default)
			)
			(layer "F.Fab")
		)
		(fp_line
			(start -0.8636 -0.4064)
			(end -0.8636 -0.4572)
			(stroke
				(width 0.1)
				(type default)
			)
			(layer "F.Fab")
		)
		(fp_line
			(start 0.8636 -0.4064)
			(end 1.1938 -0.4064)
			(stroke
				(width 0.1)
				(type default)
			)
			(layer "F.Fab")
		)
		(fp_line
			(start 1.1938 -0.4064)
			(end 1.1938 0.4064)
			(stroke
				(width 0.1)
				(type default)
			)
			(layer "F.Fab")
		)
		(fp_line
			(start -0.8636 -0.4572)
			(end 0.8636 -0.4572)
			(stroke
				(width 0.1)
				(type default)
			)
			(layer "F.Fab")
		)
		(fp_line
			(start 0.8636 -0.4572)
			(end 0.8636 -0.4064)
			(stroke
				(width 0.1)
				(type default)
			)
			(layer "F.Fab")
		)
		(pad "1" smd rect
			(at -0.7366 0 180)
			(size 0.7112 0.8128)
			(layers "F.Cu" "F.Mask" "F.Paste")
			(net "P1V25_SERDES_VDDPLL_PEX0_C3")
		)
		(pad "2" smd rect
			(at 0.7366 0 180)
			(size 0.7112 0.8128)
			(layers "F.Cu" "F.Mask" "F.Paste")
			(net "GND")
		)
	)
	(footprint ""
		(layer "F.Cu")
		(at 57.58942 -63.56223)
		(property "Reference" "Q129"
			(at -0.13462 -1.8669 0)
			(unlocked yes)
			(layer "F.SilkS")
			(effects
				(font
					(size 0.7874 0.5842)
					(thickness 0.1524)
				)
			)
		)
		(property "Value" ""
			(at 0 0 0)
			(layer "F.Fab")
			(effects
				(font
					(size 1.27 1.27)
				)
			)
		)
		(duplicate_pad_numbers_are_jumpers no)
		(fp_line
			(start -1.376172 -1.199896)
			(end -0.508 -1.199896)
			(stroke
				(width 0.1524)
				(type default)
			)
			(layer "F.SilkS")
		)
		(fp_line
			(start -1.376172 1.199896)
			(end -1.376172 -1.199896)
			(stroke
				(width 0.1524)
				(type default)
			)
			(layer "F.SilkS")
		)
		(fp_line
			(start -0.508 -1.199896)
			(end 0 -0.762)
			(stroke
				(width 0.1524)
				(type default)
			)
			(layer "F.SilkS")
		)
		(fp_line
			(start 0 -0.762)
			(end 0.508 -1.199896)
			(stroke
				(width 0.1524)
				(type default)
			)
			(layer "F.SilkS")
		)
		(fp_line
			(start 0.508 -1.199896)
			(end 1.376172 -1.199896)
			(stroke
				(width 0.1524)
				(type default)
			)
			(layer "F.SilkS")
		)
		(fp_line
			(start 1.376172 -1.199896)
			(end 1.376172 1.199896)
			(stroke
				(width 0.1524)
				(type default)
			)
			(layer "F.SilkS")
		)
		(fp_line
			(start 1.376172 1.199896)
			(end -1.376172 1.199896)
			(stroke
				(width 0.1524)
				(type default)
			)
			(layer "F.SilkS")
		)
		(fp_poly
			(pts
				(xy -1.64973 -1.121156) (xy -1.919224 -1.929384) (xy -2.457958 -1.390396)
			)
			(stroke
				(width 0)
				(type default)
			)
			(fill yes)
			(layer "F.SilkS")
		)
		(fp_line
			(start -0.674878 -1.100074)
			(end 0.674878 -1.100074)
			(stroke
				(width 0.1)
				(type default)
			)
			(layer "F.Fab")
		)
		(fp_line
			(start -0.674878 1.100074)
			(end -0.674878 -1.100074)
			(stroke
				(width 0.1)
				(type default)
			)
			(layer "F.Fab")
		)
		(fp_line
			(start 0.674878 -1.100074)
			(end 0.674878 1.100074)
			(stroke
				(width 0.1)
				(type default)
			)
			(layer "F.Fab")
		)
		(fp_line
			(start 0.674878 1.100074)
			(end -0.674878 1.100074)
			(stroke
				(width 0.1)
				(type default)
			)
			(layer "F.Fab")
		)
		(fp_poly
			(pts
				(xy -1.4605 -0.7493) (xy -2.2225 -1.1303) (xy -2.2225 -0.3683)
			)
			(stroke
				(width 0)
				(type default)
			)
			(fill yes)
			(layer "F.Fab")
		)
		(pad "1" smd rect
			(at -0.899922 -0.750062 270)
			(size 0.6096 0.6096)
			(layers "F.Cu" "F.Mask" "F.Paste")
			(net "GND")
		)
		(pad "2" smd rect
			(at -0.899922 0 270)
			(size 0.4064 0.6096)
			(layers "F.Cu" "F.Mask" "F.Paste")
			(net "P12V_SSD2_PG_G1")
		)
		(pad "3" smd rect
			(at -0.899922 0.750062 270)
			(size 0.6096 0.6096)
			(layers "F.Cu" "F.Mask" "F.Paste")
			(net "PWRGD_P12V_SSD2_D")
		)
		(pad "4" smd rect
			(at 0.899922 0.750062 270)
			(size 0.6096 0.6096)
			(layers "F.Cu" "F.Mask" "F.Paste")
			(net "GND")
		)
		(pad "5" smd rect
			(at 0.899922 0 270)
			(size 0.4064 0.6096)
			(layers "F.Cu" "F.Mask" "F.Paste")
			(net "P12V_SSD2_PG_G2")
		)
		(pad "6" smd rect
			(at 0.899922 -0.750062 270)
			(size 0.6096 0.6096)
			(layers "F.Cu" "F.Mask" "F.Paste")
			(net "P12V_SSD2_PG_G2")
		)
	)
	(footprint ""
		(layer "F.Cu")
		(at 298.74718 -196.706236 180)
		(property "Reference" "C2109"
			(at 0 0 180)
			(layer "F.SilkS")
			(hide yes)
			(effects
				(font
					(size 1.27 1.27)
				)
			)
		)
		(property "Value" ""
			(at 0 0 180)
			(layer "F.Fab")
			(effects
				(font
					(size 1.27 1.27)
				)
			)
		)
		(duplicate_pad_numbers_are_jumpers no)
		(fp_line
			(start 0.7874 0.4064)
			(end -0.7874 0.4064)
			(stroke
				(width 0.1524)
				(type default)
			)
			(layer "F.SilkS")
		)
		(fp_line
			(start 0.7874 -0.4064)
			(end 0.7874 0.4064)
			(stroke
				(width 0.1524)
				(type default)
			)
			(layer "F.SilkS")
		)
		(fp_line
			(start -0.7874 0.4064)
			(end -0.7874 -0.4064)
			(stroke
				(width 0.1524)
				(type default)
			)
			(layer "F.SilkS")
		)
		(fp_line
			(start -0.7874 -0.4064)
			(end 0.7874 -0.4064)
			(stroke
				(width 0.1524)
				(type default)
			)
			(layer "F.SilkS")
		)
		(fp_line
			(start 0.67945 0.3048)
			(end 0.120396 0.3048)
			(stroke
				(width 0.1)
				(type default)
			)
			(layer "F.Fab")
		)
		(fp_line
			(start 0.67945 -0.3048)
			(end 0.67945 0.3048)
			(stroke
				(width 0.1)
				(type default)
			)
			(layer "F.Fab")
		)
		(fp_line
			(start 0.12065 -0.2794)
			(end 0.12065 -0.3048)
			(stroke
				(width 0.1)
				(type default)
			)
			(layer "F.Fab")
		)
		(fp_line
			(start 0.12065 -0.3048)
			(end 0.67945 -0.3048)
			(stroke
				(width 0.1)
				(type default)
			)
			(layer "F.Fab")
		)
		(fp_line
			(start 0.120396 0.3048)
			(end 0.120396 0.2794)
			(stroke
				(width 0.1)
				(type default)
			)
			(layer "F.Fab")
		)
		(fp_line
			(start 0.120396 0.2794)
			(end -0.12065 0.2794)
			(stroke
				(width 0.1)
				(type default)
			)
			(layer "F.Fab")
		)
		(fp_line
			(start -0.12065 0.3048)
			(end -0.67945 0.3048)
			(stroke
				(width 0.1)
				(type default)
			)
			(layer "F.Fab")
		)
		(fp_line
			(start -0.12065 0.2794)
			(end -0.12065 0.3048)
			(stroke
				(width 0.1)
				(type default)
			)
			(layer "F.Fab")
		)
		(fp_line
			(start -0.12065 -0.2794)
			(end 0.12065 -0.2794)
			(stroke
				(width 0.1)
				(type default)
			)
			(layer "F.Fab")
		)
		(fp_line
			(start -0.12065 -0.305054)
			(end -0.12065 -0.2794)
			(stroke
				(width 0.1)
				(type default)
			)
			(layer "F.Fab")
		)
		(fp_line
			(start -0.67945 0.3048)
			(end -0.67945 -0.305054)
			(stroke
				(width 0.1)
				(type default)
			)
			(layer "F.Fab")
		)
		(fp_line
			(start -0.67945 -0.305054)
			(end -0.12065 -0.305054)
			(stroke
				(width 0.1)
				(type default)
			)
			(layer "F.Fab")
		)
		(pad "1" smd circle
			(at -0.40005 0 180)
			(size 0 0)
			(layers "F.Cu" "F.Mask" "F.Paste")
			(net "GND")
		)
		(pad "2" smd circle
			(at 0.40005 0 180)
			(size 0 0)
			(layers "F.Cu" "F.Mask" "F.Paste")
			(net "P3V3_AUX")
		)
	)
	(footprint ""
		(layer "F.Cu")
		(at 442.287914 -45.704252 90)
		(property "Reference" "R670"
			(at 0 0 90)
			(layer "F.SilkS")
			(hide yes)
			(effects
				(font
					(size 1.27 1.27)
				)
			)
		)
		(property "Value" ""
			(at 0 0 90)
			(layer "F.Fab")
			(effects
				(font
					(size 1.27 1.27)
				)
			)
		)
		(duplicate_pad_numbers_are_jumpers no)
		(fp_line
			(start 3.937508 -1.8796)
			(end -3.937508 -1.8796)
			(stroke
				(width 0.1524)
				(type default)
			)
			(layer "F.SilkS")
		)
		(fp_line
			(start -3.937508 -1.8796)
			(end -3.937508 1.8796)
			(stroke
				(width 0.1524)
				(type default)
			)
			(layer "F.SilkS")
		)
		(fp_line
			(start 3.937508 1.8796)
			(end 3.937508 -1.8796)
			(stroke
				(width 0.1524)
				(type default)
			)
			(layer "F.SilkS")
		)
		(fp_line
			(start -3.937508 1.8796)
			(end 3.937508 1.8796)
			(stroke
				(width 0.1524)
				(type default)
			)
			(layer "F.SilkS")
		)
		(fp_line
			(start 3.275076 -1.674876)
			(end -3.275076 -1.674876)
			(stroke
				(width 0.1)
				(type default)
			)
			(layer "F.Fab")
		)
		(fp_line
			(start -3.275076 -1.674876)
			(end -3.275076 1.674876)
			(stroke
				(width 0.1)
				(type default)
			)
			(layer "F.Fab")
		)
		(fp_line
			(start 3.275076 1.674876)
			(end 3.275076 -1.674876)
			(stroke
				(width 0.1)
				(type default)
			)
			(layer "F.Fab")
		)
		(fp_line
			(start -3.275076 1.674876)
			(end 3.275076 1.674876)
			(stroke
				(width 0.1)
				(type default)
			)
			(layer "F.Fab")
		)
		(pad "1" smd rect
			(at -2.350008 0 90)
			(size 2.921 3.5052)
			(layers "F.Cu" "F.Mask" "F.Paste")
			(net "P12V_SSD15")
		)
		(pad "2" smd rect
			(at 2.350008 0 90)
			(size 2.921 3.5052)
			(layers "F.Cu" "F.Mask" "F.Paste")
			(net "P12V_SSD15_R")
		)
	)
	(footprint ""
		(layer "F.Cu")
		(at 422.619932 -343.952322 90)
		(property "Reference" "C815"
			(at 0 0 90)
			(layer "F.SilkS")
			(hide yes)
			(effects
				(font
					(size 1.27 1.27)
				)
			)
		)
		(property "Value" ""
			(at 0 0 90)
			(layer "F.Fab")
			(effects
				(font
					(size 1.27 1.27)
				)
			)
		)
		(duplicate_pad_numbers_are_jumpers no)
		(fp_line
			(start 0.299974 -0.150114)
			(end 0.299974 0.150114)
			(stroke
				(width 0.1)
				(type default)
			)
			(layer "F.Fab")
		)
		(fp_line
			(start -0.299974 -0.150114)
			(end 0.299974 -0.150114)
			(stroke
				(width 0.1)
				(type default)
			)
			(layer "F.Fab")
		)
		(fp_line
			(start 0.299974 0.150114)
			(end -0.299974 0.150114)
			(stroke
				(width 0.1)
				(type default)
			)
			(layer "F.Fab")
		)
		(fp_line
			(start -0.299974 0.150114)
			(end -0.299974 -0.150114)
			(stroke
				(width 0.1)
				(type default)
			)
			(layer "F.Fab")
		)
		(pad "1" smd rect
			(at -0.2667 0 90)
			(size 0.3048 0.381)
			(layers "F.Cu" "F.Mask" "F.Paste")
			(net "P5E_PEX3_STN7_TX_DN<117>")
		)
		(pad "2" smd rect
			(at 0.2667 0 90)
			(size 0.3048 0.381)
			(layers "F.Cu" "F.Mask" "F.Paste")
			(net "P5E_PEX3_STN7_TX_C_DN<117>")
		)
	)
)
